# S9S_MB_2U (Grand Teton) — schematic netlist excerpt (pin names and nets, part order shuffled) for the footprints in the layout excerpt that follows; sources: Cadence DE-HDL packaged netlist, KiCad conversion of 03242023_DA0F0TMBIJ0_F0T_Motherboard_J_brd_V01_OCP.brd

PC1185  Q_CAPP  560UF 2.5V 20% OSCON  pkg THLF  page 272 : A = PVCCFA_EHV_FIVRA_CPU0 ; B = GND
C904  Q_CAP_DIFFBUS  DIFF BUS_0.22UF 6.3V 20% X6S  pkg C0201  page 173 : \1\ = P5E_CPU0_PE0_TX_C_DN<14> ; \2\ = P5E_CPU0_PE0_TX_DN<14>
R3816  Q_RES  100K 1% EMPTY  pkg 0402LF  page 162 : A = P3V3_AUX ; B = P12V_OCP_FAULT_2

(kicad_pcb
	(version 20260206)
	(generator "pcbnew")
	(generator_version "10.0")
	(general
		(thickness 1.6)
		(legacy_teardrops no)
	)
	(paper "A4")
	(title_block
		(title "03242023_DA0F0TMBIJ0_F0T_Motherboard_J_brd_V01_OCP.brd")
		(comment 1 "Grand Teton / footprints 527-529 of 6105")
	)
	(layers
		(0 "F.Cu" signal "TOP")
		(4 "In1.Cu" signal "GND")
		(6 "In2.Cu" signal "IN1")
		(8 "In3.Cu" signal "GND1")
		(10 "In4.Cu" signal "IN2")
		(12 "In5.Cu" signal "GND2")
		(14 "In6.Cu" signal "IN3")
		(16 "In7.Cu" signal "GND3")
		(18 "In8.Cu" signal "VCC")
		(20 "In9.Cu" signal "VCC1")
		(22 "In10.Cu" signal "GND4")
		(24 "In11.Cu" signal "IN4")
		(26 "In12.Cu" signal "GND5")
		(28 "In13.Cu" signal "IN5")
		(30 "In14.Cu" signal "GND6")
		(32 "In15.Cu" signal "IN6")
		(34 "In16.Cu" signal "GND7")
		(2 "B.Cu" signal "BOTTOM")
		(9 "F.Adhes" user "F.Adhesive")
		(11 "B.Adhes" user "B.Adhesive")
		(13 "F.Paste" user "Package Geometry/Pastemask Top")
		(15 "B.Paste" user "Package Geometry/Pastemask Bottom")
		(5 "F.SilkS" user "Ref Des/Silkscreen Top")
		(7 "B.SilkS" user "Ref Des/Silkscreen Bottom")
		(1 "F.Mask" user "Board Geometry/Soldermask Top")
		(3 "B.Mask" user "Board Geometry/Soldermask Bottom")
		(17 "Dwgs.User" user "User.Drawings")
		(19 "Cmts.User" user "User.Comments")
		(21 "Eco1.User" user "User.Eco1")
		(23 "Eco2.User" user "User.Eco2")
		(25 "Edge.Cuts" user "Board Geometry/Outline")
		(27 "Margin" user)
		(31 "F.CrtYd" user "Package Geometry/Place Bound Top")
		(29 "B.CrtYd" user "Package Geometry/Place Bound Bottom")
		(35 "F.Fab" user "Ref Des/Assembly Top")
		(33 "B.Fab" user "Ref Des/Assembly Bottom")
	)
	(footprint ""
		(layer "F.Cu")
		(at 82.706718 -21.016722 90)
		(property "Reference" "R3816"
			(at 0 0 90)
			(layer "F.SilkS")
			(hide yes)
			(effects
				(font
					(size 1.27 1.27)
				)
			)
		)
		(property "Value" ""
			(at 0 0 90)
			(layer "F.Fab")
			(effects
				(font
					(size 1.27 1.27)
				)
			)
		)
		(duplicate_pad_numbers_are_jumpers no)
		(fp_line
			(start 0.7874 -0.4064)
			(end 0.7874 0.4064)
			(stroke
				(width 0.1524)
				(type default)
			)
			(layer "F.SilkS")
		)
		(fp_line
			(start -0.7874 -0.4064)
			(end 0.7874 -0.4064)
			(stroke
				(width 0.1524)
				(type default)
			)
			(layer "F.SilkS")
		)
		(fp_line
			(start 0.7874 0.4064)
			(end -0.7874 0.4064)
			(stroke
				(width 0.1524)
				(type default)
			)
			(layer "F.SilkS")
		)
		(fp_line
			(start -0.7874 0.4064)
			(end -0.7874 -0.4064)
			(stroke
				(width 0.1524)
				(type default)
			)
			(layer "F.SilkS")
		)
		(fp_line
			(start -0.12065 -0.305054)
			(end -0.12065 -0.2794)
			(stroke
				(width 0.1)
				(type default)
			)
			(layer "F.Fab")
		)
		(fp_line
			(start -0.67945 -0.305054)
			(end -0.12065 -0.305054)
			(stroke
				(width 0.1)
				(type default)
			)
			(layer "F.Fab")
		)
		(fp_line
			(start 0.67945 -0.3048)
			(end 0.67945 0.3048)
			(stroke
				(width 0.1)
				(type default)
			)
			(layer "F.Fab")
		)
		(fp_line
			(start 0.12065 -0.3048)
			(end 0.67945 -0.3048)
			(stroke
				(width 0.1)
				(type default)
			)
			(layer "F.Fab")
		)
		(fp_line
			(start 0.12065 -0.2794)
			(end 0.12065 -0.3048)
			(stroke
				(width 0.1)
				(type default)
			)
			(layer "F.Fab")
		)
		(fp_line
			(start -0.12065 -0.2794)
			(end 0.12065 -0.2794)
			(stroke
				(width 0.1)
				(type default)
			)
			(layer "F.Fab")
		)
		(fp_line
			(start 0.120396 0.2794)
			(end -0.12065 0.2794)
			(stroke
				(width 0.1)
				(type default)
			)
			(layer "F.Fab")
		)
		(fp_line
			(start -0.12065 0.2794)
			(end -0.12065 0.3048)
			(stroke
				(width 0.1)
				(type default)
			)
			(layer "F.Fab")
		)
		(fp_line
			(start 0.67945 0.3048)
			(end 0.120396 0.3048)
			(stroke
				(width 0.1)
				(type default)
			)
			(layer "F.Fab")
		)
		(fp_line
			(start 0.120396 0.3048)
			(end 0.120396 0.2794)
			(stroke
				(width 0.1)
				(type default)
			)
			(layer "F.Fab")
		)
		(fp_line
			(start -0.12065 0.3048)
			(end -0.67945 0.3048)
			(stroke
				(width 0.1)
				(type default)
			)
			(layer "F.Fab")
		)
		(fp_line
			(start -0.67945 0.3048)
			(end -0.67945 -0.305054)
			(stroke
				(width 0.1)
				(type default)
			)
			(layer "F.Fab")
		)
		(pad "1" smd circle
			(at -0.40005 0 90)
			(size 0 0)
			(layers "F.Cu" "F.Mask" "F.Paste")
			(net "P3V3_AUX")
		)
		(pad "2" smd circle
			(at 0.40005 0 90)
			(size 0 0)
			(layers "F.Cu" "F.Mask" "F.Paste")
			(net "P12V_OCP_FAULT_2")
		)
	)
	(footprint ""
		(layer "F.Cu")
		(at 415.101786 -346.010992)
		(property "Reference" "PC1185"
			(at 0 0 0)
			(layer "F.SilkS")
			(hide yes)
			(effects
				(font
					(size 1.27 1.27)
				)
			)
		)
		(property "Value" ""
			(at 0 0 0)
			(layer "F.Fab")
			(effects
				(font
					(size 1.27 1.27)
				)
			)
		)
		(duplicate_pad_numbers_are_jumpers no)
		(fp_line
			(start 2.750058 0.999998)
			(end -2.750058 0.999998)
			(stroke
				(width 0.1524)
				(type default)
			)
			(layer "F.SilkS")
		)
		(fp_circle
			(center 0 0.999998)
			(end 2.750058 0.999998)
			(stroke
				(width 0.1524)
				(type default)
			)
			(fill no)
			(layer "F.SilkS")
		)
		(fp_poly
			(pts
				(arc
					(start 2.750058 0.999998)
					(mid 0 3.750056)
					(end -2.750058 0.999998)
				)
			)
			(stroke
				(width 0)
				(type default)
			)
			(fill yes)
			(layer "F.SilkS")
		)
		(fp_circle
			(center 0 0.999998)
			(end 2.750058 0.999998)
			(stroke
				(width 0.1)
				(type default)
			)
			(fill no)
			(layer "F.Fab")
		)
		(pad "1" thru_hole rect
			(at 0 0)
			(size 1.5748 1.5748)
			(drill 1.0668)
			(layers "*.Cu" "*.Mask")
			(remove_unused_layers no)
			(net "PVCCFA_EHV_FIVRA_CPU0")
			(clearance 0)
			(padstack
				(mode front_inner_back)
				(layer "Inner"
					(shape circle)
					(size 1.5748 1.5748)
					(clearance 0)
				)
				(layer "B.Cu"
					(shape rect)
					(size 1.5748 1.5748)
					(clearance 0)
				)
			)
		)
		(pad "2" thru_hole circle
			(at 0 1.999996)
			(size 1.5748 1.5748)
			(drill 1.0668)
			(layers "*.Cu" "*.Mask")
			(remove_unused_layers no)
			(net "GND")
			(clearance 0)
		)
	)
	(footprint ""
		(layer "F.Cu")
		(at 308.364128 -408.517344 -90)
		(property "Reference" "C904"
			(at 0 0 270)
			(layer "F.SilkS")
			(hide yes)
			(effects
				(font
					(size 1.27 1.27)
				)
			)
		)
		(property "Value" ""
			(at 0 0 270)
			(layer "F.Fab")
			(effects
				(font
					(size 1.27 1.27)
				)
			)
		)
		(duplicate_pad_numbers_are_jumpers no)
		(fp_line
			(start -0.299974 0.150114)
			(end -0.299974 -0.150114)
			(stroke
				(width 0.1)
				(type default)
			)
			(layer "F.Fab")
		)
		(fp_line
			(start 0.299974 0.150114)
			(end -0.299974 0.150114)
			(stroke
				(width 0.1)
				(type default)
			)
			(layer "F.Fab")
		)
		(fp_line
			(start -0.299974 -0.150114)
			(end 0.299974 -0.150114)
			(stroke
				(width 0.1)
				(type default)
			)
			(layer "F.Fab")
		)
		(fp_line
			(start 0.299974 -0.150114)
			(end 0.299974 0.150114)
			(stroke
				(width 0.1)
				(type default)
			)
			(layer "F.Fab")
		)
		(pad "1" smd rect
			(at -0.2667 0 270)
			(size 0.3048 0.381)
			(layers "F.Cu" "F.Mask" "F.Paste")
			(net "P5E_CPU0_PE0_TX_C_DN<14>")
		)
		(pad "2" smd rect
			(at 0.2667 0 270)
			(size 0.3048 0.381)
			(layers "F.Cu" "F.Mask" "F.Paste")
			(net "P5E_CPU0_PE0_TX_DN<14>")
		)
	)
)
